(kicad_pcb
	(version 20260206)
	(generator "pcbnew")
	(generator_version "10.0")
	(general
		(thickness 1.6)
		(legacy_teardrops no)
	)
	(paper "A4")
	(title_block
		(title "timecard-production-celestica-r4006 — R4006-B0001-02_R01.brd")
		(comment 1 "Time Appliance Project (Time Card) / footprints 862-866 of 1113")
	)
	(layers
		(0 "F.Cu" signal "TOP")
		(4 "In1.Cu" signal "L02_GND1")
		(6 "In2.Cu" signal "L03_SIG1")
		(8 "In3.Cu" signal "L04_GND2")
		(10 "In4.Cu" signal "L05_VCC1")
		(12 "In5.Cu" signal "L06_VCC2")
		(14 "In6.Cu" signal "L07_GND3")
		(16 "In7.Cu" signal "L08_SIG2")
		(18 "In8.Cu" signal "L09_GND4")
		(2 "B.Cu" signal "BOTTOM")
		(9 "F.Adhes" user "F.Adhesive")
		(11 "B.Adhes" user "B.Adhesive")
		(13 "F.Paste" user "Package Geometry/Pastemask Top")
		(15 "B.Paste" user "Package Geometry/Pastemask Bottom")
		(5 "F.SilkS" user "Ref Des/Silkscreen Top")
		(7 "B.SilkS" user "Ref Des/Silkscreen Bottom")
		(1 "F.Mask" user "Board Geometry/Soldermask Top")
		(3 "B.Mask" user "Board Geometry/Soldermask Bottom")
		(17 "Dwgs.User" user "User.Drawings")
		(19 "Cmts.User" user "User.Comments")
		(21 "Eco1.User" user "User.Eco1")
		(23 "Eco2.User" user "User.Eco2")
		(25 "Edge.Cuts" user "Board Geometry/Outline")
		(27 "Margin" user)
		(31 "F.CrtYd" user "Package Geometry/Place Bound Top")
		(29 "B.CrtYd" user "Package Geometry/Place Bound Bottom")
		(35 "F.Fab" user "Ref Des/Assembly Top")
		(33 "B.Fab" user "Ref Des/Assembly Bottom")
	)
	(footprint ""
		(layer "B.Cu")
		(at 23.0632 -71.374 90)
		(property "Reference" "R91"
			(at -1.905 1.02743 270)
			(unlocked yes)
			(layer "B.SilkS")
			(effects
				(font
					(size 0.7874 0.5842)
					(thickness 0.1524)
				)
				(justify mirror)
			)
		)
		(property "Value" "VAL*"
			(at -0.02032 2.13233 90)
			(unlocked yes)
			(layer "B.Fab")
			(hide yes)
			(effects
				(font
					(size 0.7874 0.5842)
					(thickness 0.1524)
				)
				(justify mirror)
			)
		)
		(property "Device Type" "RESISTOR-G155-133R0-01,33OHM,1%"
			(at -0.008382 1.210564 90)
			(unlocked yes)
			(layer "B.Fab")
			(hide yes)
			(effects
				(font
					(size 0.7874 0.5842)
					(thickness 0.1524)
				)
				(justify mirror)
			)
		)
		(property "User Part Number" "PARTNUM*"
			(at -0.02032 4.024884 90)
			(unlocked yes)
			(layer "Cmts.User")
			(hide yes)
			(effects
				(font
					(size 0.7874 0.5842)
					(thickness 0.1524)
				)
				(justify mirror)
			)
		)
		(property "Tolerance" "TOL*"
			(at -0.044704 3.05435 90)
			(unlocked yes)
			(layer "Cmts.User")
			(hide yes)
			(effects
				(font
					(size 0.7874 0.5842)
					(thickness 0.1524)
				)
				(justify mirror)
			)
		)
		(duplicate_pad_numbers_are_jumpers no)
		(fp_line
			(start 1.143 -0.5588)
			(end 1.143 0.5588)
			(stroke
				(width 0.1)
				(type default)
			)
			(layer "B.SilkS")
		)
		(fp_line
			(start -1.143 -0.5588)
			(end 1.143 -0.5588)
			(stroke
				(width 0.1)
				(type default)
			)
			(layer "B.SilkS")
		)
		(fp_line
			(start 1.143 0.5588)
			(end -1.143 0.5588)
			(stroke
				(width 0.1)
				(type default)
			)
			(layer "B.SilkS")
		)
		(fp_line
			(start -1.143 0.5588)
			(end -1.143 -0.5588)
			(stroke
				(width 0.1)
				(type default)
			)
			(layer "B.SilkS")
		)
		(fp_rect
			(start 1.143 0.5588)
			(end -1.143 -0.5588)
			(stroke
				(width 0)
				(type default)
			)
			(fill no)
			(layer "B.CrtYd")
		)
		(fp_line
			(start 0.508 -0.3048)
			(end 0.508 0.3048)
			(stroke
				(width 0.1)
				(type default)
			)
			(layer "B.Fab")
		)
		(fp_line
			(start -0.508 -0.3048)
			(end 0.508 -0.3048)
			(stroke
				(width 0.1)
				(type default)
			)
			(layer "B.Fab")
		)
		(fp_line
			(start 0.508 0.3048)
			(end -0.508 0.3048)
			(stroke
				(width 0.1)
				(type default)
			)
			(layer "B.Fab")
		)
		(fp_line
			(start -0.508 0.3048)
			(end -0.508 -0.3048)
			(stroke
				(width 0.1)
				(type default)
			)
			(layer "B.Fab")
		)
		(pad "1" smd rect
			(at 0.5334 0 270)
			(size 0.7112 0.6096)
			(layers "B.Cu" "B.Mask" "B.Paste")
			(net "ANALOG_TUNING_IN")
		)
		(pad "2" smd rect
			(at -0.5334 0 270)
			(size 0.7112 0.6096)
			(layers "B.Cu" "B.Mask" "B.Paste")
			(net "SMA_ANALOG_TUNING_IN")
		)
		(zone
			(layer "B.Cu")
			(hatch none 0.5)
			(connect_pads
				(clearance 0)
			)
			(min_thickness 0.25)
			(keepout
				(tracks not_allowed)
				(vias allowed)
				(pads allowed)
				(copperpour not_allowed)
				(footprints allowed)
			)
			(placement
				(enabled no)
				(sheetname "")
			)
			(fill
				(thermal_gap 0.5)
				(thermal_bridge_width 0.5)
				(island_removal_mode 0)
			)
			(polygon
				(pts
					(xy 23.368 -71.4502) (xy 22.7584 -71.4502) (xy 22.7584 -71.2978) (xy 23.368 -71.2978)
				)
			)
		)
		(zone
			(layer "B.Cu")
			(hatch none 0.5)
			(connect_pads
				(clearance 0)
			)
			(min_thickness 0.25)
			(keepout
				(tracks allowed)
				(vias not_allowed)
				(pads allowed)
				(copperpour not_allowed)
				(footprints allowed)
			)
			(placement
				(enabled no)
				(sheetname "")
			)
			(fill
				(thermal_gap 0.5)
				(thermal_bridge_width 0.5)
				(island_removal_mode 0)
			)
			(polygon
				(pts
					(xy 23.368 -71.4502) (xy 22.7584 -71.4502) (xy 22.7584 -71.2978) (xy 23.368 -71.2978)
				)
			)
		)
	)
	(footprint ""
		(layer "B.Cu")
		(at 138.4808 -74.7649 90)
		(property "Reference" "R404"
			(at -0.38227 -3.4798 0)
			(unlocked yes)
			(layer "B.SilkS")
			(effects
				(font
					(size 0.7874 0.5842)
					(thickness 0.1524)
				)
				(justify mirror)
			)
		)
		(property "Value" "VAL*"
			(at -0.02032 2.13233 90)
			(unlocked yes)
			(layer "B.Fab")
			(hide yes)
			(effects
				(font
					(size 0.7874 0.5842)
					(thickness 0.1524)
				)
				(justify mirror)
			)
		)
		(property "Device Type" "RESISTOR-G155-11002-01,10KOHM,A"
			(at -0.008382 1.210564 90)
			(unlocked yes)
			(layer "B.Fab")
			(hide yes)
			(effects
				(font
					(size 0.7874 0.5842)
					(thickness 0.1524)
				)
				(justify mirror)
			)
		)
		(property "User Part Number" "PARTNUM*"
			(at -0.02032 4.024884 90)
			(unlocked yes)
			(layer "Cmts.User")
			(hide yes)
			(effects
				(font
					(size 0.7874 0.5842)
					(thickness 0.1524)
				)
				(justify mirror)
			)
		)
		(property "Tolerance" "TOL*"
			(at -0.044704 3.05435 90)
			(unlocked yes)
			(layer "Cmts.User")
			(hide yes)
			(effects
				(font
					(size 0.7874 0.5842)
					(thickness 0.1524)
				)
				(justify mirror)
			)
		)
		(duplicate_pad_numbers_are_jumpers no)
		(fp_line
			(start 1.143 -0.5588)
			(end 1.143 0.5588)
			(stroke
				(width 0.1)
				(type default)
			)
			(layer "B.SilkS")
		)
		(fp_line
			(start -1.143 -0.5588)
			(end 1.143 -0.5588)
			(stroke
				(width 0.1)
				(type default)
			)
			(layer "B.SilkS")
		)
		(fp_line
			(start 1.143 0.5588)
			(end -1.143 0.5588)
			(stroke
				(width 0.1)
				(type default)
			)
			(layer "B.SilkS")
		)
		(fp_line
			(start -1.143 0.5588)
			(end -1.143 -0.5588)
			(stroke
				(width 0.1)
				(type default)
			)
			(layer "B.SilkS")
		)
		(fp_rect
			(start 1.143 0.5588)
			(end -1.143 -0.5588)
			(stroke
				(width 0)
				(type default)
			)
			(fill no)
			(layer "B.CrtYd")
		)
		(fp_line
			(start 0.508 -0.3048)
			(end 0.508 0.3048)
			(stroke
				(width 0.1)
				(type default)
			)
			(layer "B.Fab")
		)
		(fp_line
			(start -0.508 -0.3048)
			(end 0.508 -0.3048)
			(stroke
				(width 0.1)
				(type default)
			)
			(layer "B.Fab")
		)
		(fp_line
			(start 0.508 0.3048)
			(end -0.508 0.3048)
			(stroke
				(width 0.1)
				(type default)
			)
			(layer "B.Fab")
		)
		(fp_line
			(start -0.508 0.3048)
			(end -0.508 -0.3048)
			(stroke
				(width 0.1)
				(type default)
			)
			(layer "B.Fab")
		)
		(pad "1" smd rect
			(at 0.5334 0 270)
			(size 0.7112 0.6096)
			(layers "B.Cu" "B.Mask" "B.Paste")
			(net "XP3R3V_FPGA")
		)
		(pad "2" smd rect
			(at -0.5334 0 270)
			(size 0.7112 0.6096)
			(layers "B.Cu" "B.Mask" "B.Paste")
			(net "FPGA_TMS")
		)
		(zone
			(layer "B.Cu")
			(hatch none 0.5)
			(connect_pads
				(clearance 0)
			)
			(min_thickness 0.25)
			(keepout
				(tracks not_allowed)
				(vias allowed)
				(pads allowed)
				(copperpour not_allowed)
				(footprints allowed)
			)
			(placement
				(enabled no)
				(sheetname "")
			)
			(fill
				(thermal_gap 0.5)
				(thermal_bridge_width 0.5)
				(island_removal_mode 0)
			)
			(polygon
				(pts
					(xy 138.7856 -74.8411) (xy 138.176 -74.8411) (xy 138.176 -74.6887) (xy 138.7856 -74.6887)
				)
			)
		)
		(zone
			(layer "B.Cu")
			(hatch none 0.5)
			(connect_pads
				(clearance 0)
			)
			(min_thickness 0.25)
			(keepout
				(tracks allowed)
				(vias not_allowed)
				(pads allowed)
				(copperpour not_allowed)
				(footprints allowed)
			)
			(placement
				(enabled no)
				(sheetname "")
			)
			(fill
				(thermal_gap 0.5)
				(thermal_bridge_width 0.5)
				(island_removal_mode 0)
			)
			(polygon
				(pts
					(xy 138.7856 -74.8411) (xy 138.176 -74.8411) (xy 138.176 -74.6887) (xy 138.7856 -74.6887)
				)
			)
		)
	)
	(footprint ""
		(layer "B.Cu")
		(at 29.845 -91.059 -90)
		(property "Reference" "R463"
			(at -3.175 0.03937 270)
			(unlocked yes)
			(layer "B.SilkS")
			(effects
				(font
					(size 0.7874 0.5842)
					(thickness 0.1524)
				)
				(justify mirror)
			)
		)
		(property "Value" "VAL*"
			(at -0.0508 2.245106 270)
			(unlocked yes)
			(layer "B.Fab")
			(hide yes)
			(effects
				(font
					(size 0.7874 0.5842)
					(thickness 0.1524)
				)
				(justify mirror)
			)
		)
		(property "User Part Number" "PARTNUM*"
			(at -0.0762 4.302506 270)
			(unlocked yes)
			(layer "Cmts.User")
			(hide yes)
			(effects
				(font
					(size 0.7874 0.5842)
					(thickness 0.1524)
				)
				(justify mirror)
			)
		)
		(property "Device Type" "RESISTOR-G155-01202-01,12KOHM,A"
			(at -0.0762 1.254506 270)
			(unlocked yes)
			(layer "B.Fab")
			(hide yes)
			(effects
				(font
					(size 0.7874 0.5842)
					(thickness 0.1524)
				)
				(justify mirror)
			)
		)
		(property "Tolerance" "TOL*"
			(at -0.0508 3.261106 270)
			(unlocked yes)
			(layer "Cmts.User")
			(hide yes)
			(effects
				(font
					(size 0.7874 0.5842)
					(thickness 0.1524)
				)
				(justify mirror)
			)
		)
		(duplicate_pad_numbers_are_jumpers no)
		(fp_line
			(start -1.143 0.5588)
			(end -1.143 -0.5588)
			(stroke
				(width 0.1)
				(type default)
			)
			(layer "B.SilkS")
		)
		(fp_line
			(start 1.143 0.5588)
			(end -1.143 0.5588)
			(stroke
				(width 0.1)
				(type default)
			)
			(layer "B.SilkS")
		)
		(fp_line
			(start -1.143 -0.5588)
			(end 1.143 -0.5588)
			(stroke
				(width 0.1)
				(type default)
			)
			(layer "B.SilkS")
		)
		(fp_line
			(start 1.143 -0.5588)
			(end 1.143 0.5588)
			(stroke
				(width 0.1)
				(type default)
			)
			(layer "B.SilkS")
		)
		(fp_poly
			(pts
				(xy 1.143 0.5588) (xy -1.143 0.5588) (xy -1.143 -0.5588) (xy 1.143 -0.5588)
			)
			(stroke
				(width 0)
				(type default)
			)
			(fill no)
			(layer "B.CrtYd")
		)
		(fp_line
			(start -0.508 0.3048)
			(end -0.508 -0.3048)
			(stroke
				(width 0.1)
				(type default)
			)
			(layer "B.Fab")
		)
		(fp_line
			(start 0.508 0.3048)
			(end -0.508 0.3048)
			(stroke
				(width 0.1)
				(type default)
			)
			(layer "B.Fab")
		)
		(fp_line
			(start -0.508 -0.3048)
			(end 0.508 -0.3048)
			(stroke
				(width 0.1)
				(type default)
			)
			(layer "B.Fab")
		)
		(fp_line
			(start 0.508 -0.3048)
			(end 0.508 0.3048)
			(stroke
				(width 0.1)
				(type default)
			)
			(layer "B.Fab")
		)
		(pad "1" smd rect
			(at 0.5334 0 90)
			(size 0.7112 0.6096)
			(layers "B.Cu" "B.Mask" "B.Paste")
			(net "UNNAMED_524_FT4232HLREELQFP64_6")
		)
		(pad "2" smd rect
			(at -0.5334 0 90)
			(size 0.7112 0.6096)
			(layers "B.Cu" "B.Mask" "B.Paste")
			(net "SG")
		)
		(zone
			(layer "B.Cu")
			(hatch none 0.5)
			(connect_pads
				(clearance 0)
			)
			(min_thickness 0.25)
			(keepout
				(tracks allowed)
				(vias not_allowed)
				(pads allowed)
				(copperpour not_allowed)
				(footprints allowed)
			)
			(placement
				(enabled no)
				(sheetname "")
			)
			(fill
				(thermal_gap 0.5)
				(thermal_bridge_width 0.5)
				(island_removal_mode 0)
			)
			(polygon
				(pts
					(xy 29.5402 -90.9828) (xy 30.1498 -90.9828) (xy 30.1498 -91.1352) (xy 29.5402 -91.1352)
				)
			)
		)
		(zone
			(layer "B.Cu")
			(hatch none 0.5)
			(connect_pads
				(clearance 0)
			)
			(min_thickness 0.25)
			(keepout
				(tracks not_allowed)
				(vias allowed)
				(pads allowed)
				(copperpour not_allowed)
				(footprints allowed)
			)
			(placement
				(enabled no)
				(sheetname "")
			)
			(fill
				(thermal_gap 0.5)
				(thermal_bridge_width 0.5)
				(island_removal_mode 0)
			)
			(polygon
				(pts
					(xy 29.5402 -90.9828) (xy 30.1498 -90.9828) (xy 30.1498 -91.1352) (xy 29.5402 -91.1352)
				)
			)
		)
	)
	(footprint ""
		(layer "B.Cu")
		(at 140.335 -76.708)
		(property "Reference" "R137"
			(at 0 -2.24663 0)
			(unlocked yes)
			(layer "B.SilkS")
			(effects
				(font
					(size 0.7874 0.5842)
					(thickness 0.1524)
				)
				(justify mirror)
			)
		)
		(property "Value" "VAL*"
			(at -0.02032 2.13233 0)
			(unlocked yes)
			(layer "B.Fab")
			(hide yes)
			(effects
				(font
					(size 0.7874 0.5842)
					(thickness 0.1524)
				)
				(justify mirror)
			)
		)
		(property "Tolerance" "TOL*"
			(at -0.044704 3.05435 0)
			(unlocked yes)
			(layer "Cmts.User")
			(hide yes)
			(effects
				(font
					(size 0.7874 0.5842)
					(thickness 0.1524)
				)
				(justify mirror)
			)
		)
		(property "User Part Number" "PARTNUM*"
			(at -0.02032 4.024884 0)
			(unlocked yes)
			(layer "Cmts.User")
			(hide yes)
			(effects
				(font
					(size 0.7874 0.5842)
					(thickness 0.1524)
				)
				(justify mirror)
			)
		)
		(property "Device Type" "RESISTOR-G155-133R0-01,33OHM,1%"
			(at -0.008382 1.210564 0)
			(unlocked yes)
			(layer "B.Fab")
			(hide yes)
			(effects
				(font
					(size 0.7874 0.5842)
					(thickness 0.1524)
				)
				(justify mirror)
			)
		)
		(duplicate_pad_numbers_are_jumpers no)
		(fp_line
			(start -1.143 -0.5588)
			(end 1.143 -0.5588)
			(stroke
				(width 0.1)
				(type default)
			)
			(layer "B.SilkS")
		)
		(fp_line
			(start -1.143 0.5588)
			(end -1.143 -0.5588)
			(stroke
				(width 0.1)
				(type default)
			)
			(layer "B.SilkS")
		)
		(fp_line
			(start 1.143 -0.5588)
			(end 1.143 0.5588)
			(stroke
				(width 0.1)
				(type default)
			)
			(layer "B.SilkS")
		)
		(fp_line
			(start 1.143 0.5588)
			(end -1.143 0.5588)
			(stroke
				(width 0.1)
				(type default)
			)
			(layer "B.SilkS")
		)
		(fp_rect
			(start 1.143 0.5588)
			(end -1.143 -0.5588)
			(stroke
				(width 0)
				(type default)
			)
			(fill no)
			(layer "B.CrtYd")
		)
		(fp_line
			(start -0.508 -0.3048)
			(end 0.508 -0.3048)
			(stroke
				(width 0.1)
				(type default)
			)
			(layer "B.Fab")
		)
		(fp_line
			(start -0.508 0.3048)
			(end -0.508 -0.3048)
			(stroke
				(width 0.1)
				(type default)
			)
			(layer "B.Fab")
		)
		(fp_line
			(start 0.508 -0.3048)
			(end 0.508 0.3048)
			(stroke
				(width 0.1)
				(type default)
			)
			(layer "B.Fab")
		)
		(fp_line
			(start 0.508 0.3048)
			(end -0.508 0.3048)
			(stroke
				(width 0.1)
				(type default)
			)
			(layer "B.Fab")
		)
		(pad "1" smd rect
			(at 0.5334 0 180)
			(size 0.7112 0.6096)
			(layers "B.Cu" "B.Mask" "B.Paste")
			(net "FT4232_FPGA_TDI")
		)
		(pad "2" smd rect
			(at -0.5334 0 180)
			(size 0.7112 0.6096)
			(layers "B.Cu" "B.Mask" "B.Paste")
			(net "FPGA_TDI")
		)
		(zone
			(layer "B.Cu")
			(hatch none 0.5)
			(connect_pads
				(clearance 0)
			)
			(min_thickness 0.25)
			(keepout
				(tracks allowed)
				(vias not_allowed)
				(pads allowed)
				(copperpour not_allowed)
				(footprints allowed)
			)
			(placement
				(enabled no)
				(sheetname "")
			)
			(fill
				(thermal_gap 0.5)
				(thermal_bridge_width 0.5)
				(island_removal_mode 0)
			)
			(polygon
				(pts
					(xy 140.4112 -76.4032) (xy 140.4112 -77.0128) (xy 140.2588 -77.0128) (xy 140.2588 -76.4032)
				)
			)
		)
	)
	(footprint ""
		(layer "B.Cu")
		(at 22.3012 -23.6728 90)
		(property "Reference" "R159"
			(at 2.6162 0.01143 270)
			(unlocked yes)
			(layer "B.SilkS")
			(effects
				(font
					(size 0.7874 0.5842)
					(thickness 0.1524)
				)
				(justify mirror)
			)
		)
		(property "Value" "VAL*"
			(at -0.02032 2.13233 90)
			(unlocked yes)
			(layer "B.Fab")
			(hide yes)
			(effects
				(font
					(size 0.7874 0.5842)
					(thickness 0.1524)
				)
				(justify mirror)
			)
		)
		(property "Tolerance" "TOL*"
			(at -0.044704 3.05435 90)
			(unlocked yes)
			(layer "Cmts.User")
			(hide yes)
			(effects
				(font
					(size 0.7874 0.5842)
					(thickness 0.1524)
				)
				(justify mirror)
			)
		)
		(property "User Part Number" "PARTNUM*"
			(at -0.02032 4.024884 90)
			(unlocked yes)
			(layer "Cmts.User")
			(hide yes)
			(effects
				(font
					(size 0.7874 0.5842)
					(thickness 0.1524)
				)
				(justify mirror)
			)
		)
		(property "Device Type" "RESISTOR-G155-14701-01,4.7KOHMA"
			(at -0.008382 1.210564 90)
			(unlocked yes)
			(layer "B.Fab")
			(hide yes)
			(effects
				(font
					(size 0.7874 0.5842)
					(thickness 0.1524)
				)
				(justify mirror)
			)
		)
		(duplicate_pad_numbers_are_jumpers no)
		(fp_line
			(start 1.143 -0.5588)
			(end 1.143 0.5588)
			(stroke
				(width 0.1)
				(type default)
			)
			(layer "B.SilkS")
		)
		(fp_line
			(start -1.143 -0.5588)
			(end 1.143 -0.5588)
			(stroke
				(width 0.1)
				(type default)
			)
			(layer "B.SilkS")
		)
		(fp_line
			(start 1.143 0.5588)
			(end -1.143 0.5588)
			(stroke
				(width 0.1)
				(type default)
			)
			(layer "B.SilkS")
		)
		(fp_line
			(start -1.143 0.5588)
			(end -1.143 -0.5588)
			(stroke
				(width 0.1)
				(type default)
			)
			(layer "B.SilkS")
		)
		(fp_rect
			(start 1.143 -0.5588)
			(end -1.143 0.5588)
			(stroke
				(width 0)
				(type default)
			)
			(fill no)
			(layer "B.CrtYd")
		)
		(fp_line
			(start 0.508 -0.3048)
			(end 0.508 0.3048)
			(stroke
				(width 0.1)
				(type default)
			)
			(layer "B.Fab")
		)
		(fp_line
			(start -0.508 -0.3048)
			(end 0.508 -0.3048)
			(stroke
				(width 0.1)
				(type default)
			)
			(layer "B.Fab")
		)
		(fp_line
			(start 0.508 0.3048)
			(end -0.508 0.3048)
			(stroke
				(width 0.1)
				(type default)
			)
			(layer "B.Fab")
		)
		(fp_line
			(start -0.508 0.3048)
			(end -0.508 -0.3048)
			(stroke
				(width 0.1)
				(type default)
			)
			(layer "B.Fab")
		)
		(pad "1" smd rect
			(at 0.5334 0 270)
			(size 0.7112 0.6096)
			(layers "B.Cu" "B.Mask" "B.Paste")
			(net "UNNAMED_5_24LC16BTISTTSSOP8_I15")
		)
		(pad "2" smd rect
			(at -0.5334 0 270)
			(size 0.7112 0.6096)
			(layers "B.Cu" "B.Mask" "B.Paste")
			(net "SG")
		)
		(zone
			(layer "B.Cu")
			(hatch none 0.5)
			(connect_pads
				(clearance 0)
			)
			(min_thickness 0.25)
			(keepout
				(tracks allowed)
				(vias not_allowed)
				(pads allowed)
				(copperpour not_allowed)
				(footprints allowed)
			)
			(placement
				(enabled no)
				(sheetname "")
			)
			(fill
				(thermal_gap 0.5)
				(thermal_bridge_width 0.5)
				(island_removal_mode 0)
			)
			(polygon
				(pts
					(xy 21.9964 -23.749) (xy 21.9964 -23.5966) (xy 22.606 -23.5966) (xy 22.606 -23.749)
				)
			)
		)
	)
)
